# T6G (Grand Teton) — schematic netlist excerpt (pin names and nets, part order shuffled) for the footprints in the layout excerpt that follows; sources: Cadence DE-HDL packaged netlist, KiCad conversion of 04192023_DAF0TMB3IC0_F0TG_MB_C_brd_V02_OCP.brd

C692  Q_CAP_DIFFBUS  DIFF BUS_0.22UF 6.3V 20% X6S  pkg C0201  page 67 : \1\ = P5E_CPU1_G1_TX_C_DN<8> ; \2\ = P5E_CPU1_G1_TX_DN<8>
R1420  Q_RES  1K 1% CHIP  pkg 0201LF  page 185 : A = P1V8_CPU0_RT_1D ; B = SMB_RT_CPU0_P3_ROM_MUX_1D_SDA
R6277  Q_RES  10K 1% EMPTY  pkg 0402LF  page 179 : A = P3V3_AUX ; B = USB_HUB2_MRP_PRT_CTL4_GANGPWR

(kicad_pcb
	(version 20260206)
	(generator "pcbnew")
	(generator_version "10.0")
	(general
		(thickness 1.6)
		(legacy_teardrops no)
	)
	(paper "A4")
	(title_block
		(title "04192023_DAF0TMB3IC0_F0TG_MB_C_brd_V02_OCP.brd")
		(comment 1 "Grand Teton / footprints 3044-3046 of 8354")
	)
	(layers
		(0 "F.Cu" signal "TOP")
		(4 "In1.Cu" signal "GND")
		(6 "In2.Cu" signal "IN1")
		(8 "In3.Cu" signal "GND1")
		(10 "In4.Cu" signal "IN2")
		(12 "In5.Cu" signal "GND2")
		(14 "In6.Cu" signal "IN3")
		(16 "In7.Cu" signal "GND3")
		(18 "In8.Cu" signal "VCC")
		(20 "In9.Cu" signal "VCC1")
		(22 "In10.Cu" signal "GND4")
		(24 "In11.Cu" signal "IN4")
		(26 "In12.Cu" signal "GND5")
		(28 "In13.Cu" signal "IN5")
		(30 "In14.Cu" signal "GND6")
		(32 "In15.Cu" signal "IN6")
		(34 "In16.Cu" signal "GND7")
		(2 "B.Cu" signal "BOTTOM")
		(9 "F.Adhes" user "F.Adhesive")
		(11 "B.Adhes" user "B.Adhesive")
		(13 "F.Paste" user "Package Geometry/Pastemask Top")
		(15 "B.Paste" user "Package Geometry/Pastemask Bottom")
		(5 "F.SilkS" user "Ref Des/Silkscreen Top")
		(7 "B.SilkS" user "Ref Des/Silkscreen Bottom")
		(1 "F.Mask" user "Board Geometry/Soldermask Top")
		(3 "B.Mask" user "Board Geometry/Soldermask Bottom")
		(17 "Dwgs.User" user "User.Drawings")
		(19 "Cmts.User" user "User.Comments")
		(21 "Eco1.User" user "User.Eco1")
		(23 "Eco2.User" user "User.Eco2")
		(25 "Edge.Cuts" user "Board Geometry/Outline")
		(27 "Margin" user)
		(31 "F.CrtYd" user "Package Geometry/Place Bound Top")
		(29 "B.CrtYd" user "Package Geometry/Place Bound Bottom")
		(35 "F.Fab" user "Ref Des/Assembly Top")
		(33 "B.Fab" user "Ref Des/Assembly Bottom")
	)
	(footprint ""
		(layer "F.Cu")
		(at 124.840238 -42.57675 180)
		(property "Reference" "R6277"
			(at 0 0 180)
			(layer "F.SilkS")
			(hide yes)
			(effects
				(font
					(size 1.27 1.27)
				)
			)
		)
		(property "Value" ""
			(at 0 0 180)
			(layer "F.Fab")
			(effects
				(font
					(size 1.27 1.27)
				)
			)
		)
		(duplicate_pad_numbers_are_jumpers no)
		(fp_line
			(start 0.7874 0.4064)
			(end -0.7874 0.4064)
			(stroke
				(width 0.1524)
				(type default)
			)
			(layer "F.SilkS")
		)
		(fp_line
			(start 0.7874 -0.4064)
			(end 0.7874 0.4064)
			(stroke
				(width 0.1524)
				(type default)
			)
			(layer "F.SilkS")
		)
		(fp_line
			(start -0.7874 0.4064)
			(end -0.7874 -0.4064)
			(stroke
				(width 0.1524)
				(type default)
			)
			(layer "F.SilkS")
		)
		(fp_line
			(start -0.7874 -0.4064)
			(end 0.7874 -0.4064)
			(stroke
				(width 0.1524)
				(type default)
			)
			(layer "F.SilkS")
		)
		(fp_line
			(start 0.67945 0.3048)
			(end 0.120396 0.3048)
			(stroke
				(width 0.1)
				(type default)
			)
			(layer "F.Fab")
		)
		(fp_line
			(start 0.67945 -0.3048)
			(end 0.67945 0.3048)
			(stroke
				(width 0.1)
				(type default)
			)
			(layer "F.Fab")
		)
		(fp_line
			(start 0.12065 -0.2794)
			(end 0.12065 -0.3048)
			(stroke
				(width 0.1)
				(type default)
			)
			(layer "F.Fab")
		)
		(fp_line
			(start 0.12065 -0.3048)
			(end 0.67945 -0.3048)
			(stroke
				(width 0.1)
				(type default)
			)
			(layer "F.Fab")
		)
		(fp_line
			(start 0.120396 0.3048)
			(end 0.120396 0.2794)
			(stroke
				(width 0.1)
				(type default)
			)
			(layer "F.Fab")
		)
		(fp_line
			(start 0.120396 0.2794)
			(end -0.12065 0.2794)
			(stroke
				(width 0.1)
				(type default)
			)
			(layer "F.Fab")
		)
		(fp_line
			(start -0.12065 0.3048)
			(end -0.67945 0.3048)
			(stroke
				(width 0.1)
				(type default)
			)
			(layer "F.Fab")
		)
		(fp_line
			(start -0.12065 0.2794)
			(end -0.12065 0.3048)
			(stroke
				(width 0.1)
				(type default)
			)
			(layer "F.Fab")
		)
		(fp_line
			(start -0.12065 -0.2794)
			(end 0.12065 -0.2794)
			(stroke
				(width 0.1)
				(type default)
			)
			(layer "F.Fab")
		)
		(fp_line
			(start -0.12065 -0.305054)
			(end -0.12065 -0.2794)
			(stroke
				(width 0.1)
				(type default)
			)
			(layer "F.Fab")
		)
		(fp_line
			(start -0.67945 0.3048)
			(end -0.67945 -0.305054)
			(stroke
				(width 0.1)
				(type default)
			)
			(layer "F.Fab")
		)
		(fp_line
			(start -0.67945 -0.305054)
			(end -0.12065 -0.305054)
			(stroke
				(width 0.1)
				(type default)
			)
			(layer "F.Fab")
		)
		(pad "1" smd circle
			(at -0.40005 0 180)
			(size 0 0)
			(layers "F.Cu" "F.Mask" "F.Paste")
			(net "P3V3_AUX")
		)
		(pad "2" smd circle
			(at 0.40005 0 180)
			(size 0 0)
			(layers "F.Cu" "F.Mask" "F.Paste")
			(net "USB_HUB2_MRP_PRT_CTL4_GANGPWR")
		)
	)
	(footprint ""
		(layer "F.Cu")
		(at 35.066478 -17.623536 90)
		(property "Reference" "C692"
			(at 0 0 90)
			(layer "F.SilkS")
			(hide yes)
			(effects
				(font
					(size 1.27 1.27)
				)
			)
		)
		(property "Value" ""
			(at 0 0 90)
			(layer "F.Fab")
			(effects
				(font
					(size 1.27 1.27)
				)
			)
		)
		(duplicate_pad_numbers_are_jumpers no)
		(fp_line
			(start 0.299974 -0.150114)
			(end 0.299974 0.150114)
			(stroke
				(width 0.1)
				(type default)
			)
			(layer "F.Fab")
		)
		(fp_line
			(start -0.299974 -0.150114)
			(end 0.299974 -0.150114)
			(stroke
				(width 0.1)
				(type default)
			)
			(layer "F.Fab")
		)
		(fp_line
			(start 0.299974 0.150114)
			(end -0.299974 0.150114)
			(stroke
				(width 0.1)
				(type default)
			)
			(layer "F.Fab")
		)
		(fp_line
			(start -0.299974 0.150114)
			(end -0.299974 -0.150114)
			(stroke
				(width 0.1)
				(type default)
			)
			(layer "F.Fab")
		)
		(pad "1" smd rect
			(at -0.2667 0 90)
			(size 0.3048 0.381)
			(layers "F.Cu" "F.Mask" "F.Paste")
			(net "P5E_CPU1_G1_TX_C_DN<8>")
		)
		(pad "2" smd rect
			(at 0.2667 0 90)
			(size 0.3048 0.381)
			(layers "F.Cu" "F.Mask" "F.Paste")
			(net "P5E_CPU1_G1_TX_DN<8>")
		)
	)
	(footprint ""
		(layer "F.Cu")
		(at 365.7854 -426.604176)
		(property "Reference" "R1420"
			(at 0 0 0)
			(layer "F.SilkS")
			(hide yes)
			(effects
				(font
					(size 1.27 1.27)
				)
			)
		)
		(property "Value" ""
			(at 0 0 0)
			(layer "F.Fab")
			(effects
				(font
					(size 1.27 1.27)
				)
			)
		)
		(duplicate_pad_numbers_are_jumpers no)
		(fp_line
			(start -0.32512 -0.175006)
			(end 0.32512 -0.175006)
			(stroke
				(width 0.1)
				(type default)
			)
			(layer "F.Fab")
		)
		(fp_line
			(start -0.32512 0.175006)
			(end -0.32512 -0.175006)
			(stroke
				(width 0.1)
				(type default)
			)
			(layer "F.Fab")
		)
		(fp_line
			(start 0.32512 -0.175006)
			(end 0.32512 0.175006)
			(stroke
				(width 0.1)
				(type default)
			)
			(layer "F.Fab")
		)
		(fp_line
			(start 0.32512 0.175006)
			(end -0.32512 0.175006)
			(stroke
				(width 0.1)
				(type default)
			)
			(layer "F.Fab")
		)
		(pad "1" smd rect
			(at -0.2667 0)
			(size 0.3048 0.381)
			(layers "F.Cu" "F.Mask" "F.Paste")
			(net "P1V8_CPU0_RT_1D")
		)
		(pad "2" smd rect
			(at 0.2667 0 180)
			(size 0.3048 0.381)
			(layers "F.Cu" "F.Mask" "F.Paste")
			(net "SMB_RT_CPU0_P3_ROM_MUX_1D_SDA")
		)
	)
)
